(kicad_pcb
	(version 20221018)
	(generator pcbnew)
	(general
    (thickness 1.7403)
  )
	(paper "A4")
	(title_block
    (title "Data Center RDIMM DDR4 Tester")
    (date "2024-09-30")
    (rev "1.2.4")
		(comment 9 "footprints 448-457 of 690")
	)
	(layers
    (0 "F.Cu" signal)
    (1 "In1.Cu" power)
    (2 "In2.Cu" signal)
    (3 "In3.Cu" power)
    (4 "In4.Cu" power)
    (5 "In5.Cu" signal)
    (6 "In6.Cu" power)
    (7 "In7.Cu" signal)
    (8 "In8.Cu" power)
    (9 "In9.Cu" signal)
    (10 "In10.Cu" power)
    (31 "B.Cu" signal)
    (32 "B.Adhes" user "B.Adhesive")
    (33 "F.Adhes" user "F.Adhesive")
    (34 "B.Paste" user)
    (35 "F.Paste" user)
    (36 "B.SilkS" user "B.Silkscreen")
    (37 "F.SilkS" user "F.Silkscreen")
    (38 "B.Mask" user)
    (39 "F.Mask" user)
    (40 "Dwgs.User" user "User.Drawings")
    (41 "Cmts.User" user "User.Comments")
    (42 "Eco1.User" user "User.Eco1")
    (43 "Eco2.User" user "User.Eco2")
    (44 "Edge.Cuts" user)
    (45 "Margin" user)
    (46 "B.CrtYd" user "B.Courtyard")
    (47 "F.CrtYd" user "F.Courtyard")
    (48 "B.Fab" user)
    (49 "F.Fab" user)
  )
	(footprint "data-center-rdimm-ddr4-tester-footprints:C_0201" (layer "B.Cu")
    (at 184.186328 93.560008 90)
    (descr "Capacitor SMD 0201")
    (tags "capacitor SMD 0201")
    (property "Author" "Antmicro")
    (property "Dielectric" "")
    (property "License" "Apache-2.0")
    (property "MPN" "CC0201KRX6S5BB104")
    (property "Manufacturer" "Yaego")
    (property "Sheetfile" "fpga-power.kicad_sch")
    (property "Sheetname" "FPGA power")
    (property "Val" "100n")
    (property "Voltage" "")
    (property "ki_description" " ")
    (attr smd)
    (fp_text reference "C69" (at 10.360008 18.343672 270) (layer "B.SilkS")
        (effects (font (size 0.7 0.7) (thickness 0.15)) (justify left bottom mirror))
    )
    (fp_text value "C_100n_0201" (at 0 -1.4 270) (layer "B.Fab") hide
        (effects (font (size 0.7 0.7) (thickness 0.15)) (justify left bottom mirror))
    )
    (fp_text user "Author: Antmicro" (at -0.72 -5.4 270) (layer "B.Fab") hide
        (effects (font (size 0.7 0.7) (thickness 0.15)) (justify left bottom mirror))
    )
    (fp_text user "${REFERENCE}" (at -0.72 -3.4 270) (layer "B.Fab") hide
        (effects (font (size 0.7 0.7) (thickness 0.15)) (justify left bottom mirror))
    )
    (fp_text user "License: Apache-2.0" (at -0.72 -4.4 270) (layer "B.Fab") hide
        (effects (font (size 0.7 0.7) (thickness 0.15)) (justify left bottom mirror))
    )
    (fp_rect (start -0.72 0.38) (end 0.72 -0.38)
      (stroke (width 0.05) (type solid)) (fill none) (layer "B.CrtYd"))
    (fp_rect (start 0.3 -0.15) (end -0.301 0.149)
      (stroke (width 0.15) (type solid)) (fill none) (layer "B.Fab"))
    (pad "" smd roundrect (at -0.349 0.002 90) (size 0.318 0.36) (layers "B.Paste") (roundrect_rratio 0.25))
    (pad "" smd roundrect (at 0.341 0.002 90) (size 0.318 0.36) (layers "B.Paste") (roundrect_rratio 0.25))
    (pad "1" smd roundrect (at -0.321 0.002 90) (size 0.46 0.4) (layers "B.Cu" "B.Mask") (roundrect_rratio 0.25)
      (net 147 "1V0_SYS") (pintype "passive"))
    (pad "2" smd roundrect (at 0.32 0.002 90) (size 0.46 0.4) (layers "B.Cu" "B.Mask") (roundrect_rratio 0.25)
      (net 9 "GND") (pintype "passive"))
  )
	(footprint "data-center-rdimm-ddr4-tester-footprints:C_0201" (layer "B.Cu")
    (at 180.936328 93.710008 180)
    (descr "Capacitor SMD 0201")
    (tags "capacitor SMD 0201")
    (property "Author" "Antmicro")
    (property "Dielectric" "")
    (property "License" "Apache-2.0")
    (property "MPN" "CC0201KRX6S5BB104")
    (property "Manufacturer" "Yaego")
    (property "Sheetfile" "fpga-power.kicad_sch")
    (property "Sheetname" "FPGA power")
    (property "Val" "100n")
    (property "Voltage" "")
    (property "ki_description" " ")
    (attr smd)
    (fp_text reference "C70" (at 0.516328 -0.399992) (layer "B.SilkS")
        (effects (font (size 0.7 0.7) (thickness 0.15)) (justify left bottom mirror))
    )
    (fp_text value "C_100n_0201" (at 0 -1.4) (layer "B.Fab") hide
        (effects (font (size 0.7 0.7) (thickness 0.15)) (justify left bottom mirror))
    )
    (fp_text user "License: Apache-2.0" (at -0.72 -4.4) (layer "B.Fab") hide
        (effects (font (size 0.7 0.7) (thickness 0.15)) (justify left bottom mirror))
    )
    (fp_text user "${REFERENCE}" (at -0.72 -3.4) (layer "B.Fab") hide
        (effects (font (size 0.7 0.7) (thickness 0.15)) (justify left bottom mirror))
    )
    (fp_text user "Author: Antmicro" (at -0.72 -5.4) (layer "B.Fab") hide
        (effects (font (size 0.7 0.7) (thickness 0.15)) (justify left bottom mirror))
    )
    (fp_rect (start -0.72 0.38) (end 0.72 -0.38)
      (stroke (width 0.05) (type solid)) (fill none) (layer "B.CrtYd"))
    (fp_rect (start 0.3 -0.15) (end -0.301 0.149)
      (stroke (width 0.15) (type solid)) (fill none) (layer "B.Fab"))
    (pad "" smd roundrect (at -0.349 0.002 180) (size 0.318 0.36) (layers "B.Paste") (roundrect_rratio 0.25))
    (pad "" smd roundrect (at 0.341 0.002 180) (size 0.318 0.36) (layers "B.Paste") (roundrect_rratio 0.25))
    (pad "1" smd roundrect (at -0.321 0.002 180) (size 0.46 0.4) (layers "B.Cu" "B.Mask") (roundrect_rratio 0.25)
      (net 147 "1V0_SYS") (pintype "passive"))
    (pad "2" smd roundrect (at 0.32 0.002 180) (size 0.46 0.4) (layers "B.Cu" "B.Mask") (roundrect_rratio 0.25)
      (net 9 "GND") (pintype "passive"))
  )
	(footprint "data-center-rdimm-ddr4-tester-footprints:C_0201" (layer "B.Cu")
    (at 187.136328 94.510008 180)
    (descr "Capacitor SMD 0201")
    (tags "capacitor SMD 0201")
    (property "Author" "Antmicro")
    (property "Dielectric" "")
    (property "License" "Apache-2.0")
    (property "MPN" "CC0201KRX6S5BB104")
    (property "Manufacturer" "Yaego")
    (property "Sheetfile" "fpga-power.kicad_sch")
    (property "Sheetname" "FPGA power")
    (property "Val" "100n")
    (property "Voltage" "")
    (property "ki_description" " ")
    (attr smd)
    (fp_text reference "C77" (at -1.113672 -1.099992) (layer "B.SilkS")
        (effects (font (size 0.7 0.7) (thickness 0.15)) (justify left bottom mirror))
    )
    (fp_text value "C_100n_0201" (at 0 -1.4) (layer "B.Fab") hide
        (effects (font (size 0.7 0.7) (thickness 0.15)) (justify left bottom mirror))
    )
    (fp_text user "${REFERENCE}" (at -0.72 -3.4) (layer "B.Fab") hide
        (effects (font (size 0.7 0.7) (thickness 0.15)) (justify left bottom mirror))
    )
    (fp_text user "License: Apache-2.0" (at -0.72 -4.4) (layer "B.Fab") hide
        (effects (font (size 0.7 0.7) (thickness 0.15)) (justify left bottom mirror))
    )
    (fp_text user "Author: Antmicro" (at -0.72 -5.4) (layer "B.Fab") hide
        (effects (font (size 0.7 0.7) (thickness 0.15)) (justify left bottom mirror))
    )
    (fp_rect (start -0.72 0.38) (end 0.72 -0.38)
      (stroke (width 0.05) (type solid)) (fill none) (layer "B.CrtYd"))
    (fp_rect (start 0.3 -0.15) (end -0.301 0.149)
      (stroke (width 0.15) (type solid)) (fill none) (layer "B.Fab"))
    (pad "" smd roundrect (at -0.349 0.002 180) (size 0.318 0.36) (layers "B.Paste") (roundrect_rratio 0.25))
    (pad "" smd roundrect (at 0.341 0.002 180) (size 0.318 0.36) (layers "B.Paste") (roundrect_rratio 0.25))
    (pad "1" smd roundrect (at -0.321 0.002 180) (size 0.46 0.4) (layers "B.Cu" "B.Mask") (roundrect_rratio 0.25)
      (net 147 "1V0_SYS") (pintype "passive"))
    (pad "2" smd roundrect (at 0.32 0.002 180) (size 0.46 0.4) (layers "B.Cu" "B.Mask") (roundrect_rratio 0.25)
      (net 9 "GND") (pintype "passive"))
  )
	(footprint "data-center-rdimm-ddr4-tester-footprints:C_0402_1005Metric" (layer "B.Cu")
    (at 185.5 88.3 -90)
    (descr "Capacitor SMD 0402")
    (tags "capacitor SMD 0402")
    (property "Author" "Antmicro")
    (property "Dielectric" "")
    (property "License" "Apache-2.0")
    (property "MPN" "GRM155R61A475MEAAD")
    (property "Manufacturer" "Murata")
    (property "Sheetfile" "fpga-power.kicad_sch")
    (property "Sheetname" "FPGA power")
    (property "Val" "4u7")
    (property "Voltage" "")
    (property "ki_description" " ")
    (attr smd)
    (fp_text reference "C144" (at -10.49 -18.49 90) (layer "B.SilkS")
        (effects (font (size 0.7 0.7) (thickness 0.15)) (justify left bottom mirror))
    )
    (fp_text value "C_4u7_0402" (at 0 -1.4 90) (layer "B.Fab") hide
        (effects (font (size 0.7 0.7) (thickness 0.15)) (justify left bottom mirror))
    )
    (fp_text user "Author: Antmicro" (at -0.932 -4.17 90) (layer "B.Fab") hide
        (effects (font (size 0.7 0.7) (thickness 0.15)) (justify left bottom mirror))
    )
    (fp_text user "${REFERENCE}" (at -0.932 -3.168 90) (layer "B.Fab") hide
        (effects (font (size 0.7 0.7) (thickness 0.15)) (justify left bottom mirror))
    )
    (fp_text user "License: Apache-2.0" (at -0.932 -5.17 90) (layer "B.Fab") hide
        (effects (font (size 0.7 0.7) (thickness 0.15)) (justify left bottom mirror))
    )
    (fp_rect (start -0.94 0.47) (end 0.94 -0.47)
      (stroke (width 0.05) (type solid)) (fill none) (layer "B.CrtYd"))
    (fp_rect (start -0.499 0.249) (end 0.499 -0.249)
      (stroke (width 0.15) (type solid)) (fill none) (layer "B.Fab"))
    (pad "1" smd roundrect (at -0.484 0 270) (size 0.59 0.64) (layers "B.Cu" "B.Paste" "B.Mask") (roundrect_rratio 0.25)
      (net 147 "1V0_SYS") (pintype "passive"))
    (pad "2" smd roundrect (at 0.484 0 270) (size 0.59 0.64) (layers "B.Cu" "B.Paste" "B.Mask") (roundrect_rratio 0.25)
      (net 9 "GND") (pintype "passive"))
  )
	(footprint "data-center-rdimm-ddr4-tester-footprints:C_0402_1005Metric" (layer "B.Cu")
    (at 181.75 90.15)
    (descr "Capacitor SMD 0402")
    (tags "capacitor SMD 0402")
    (property "Author" "Antmicro")
    (property "Dielectric" "")
    (property "License" "Apache-2.0")
    (property "MPN" "GRM155R61A475MEAAD")
    (property "Manufacturer" "Murata")
    (property "Sheetfile" "fpga-power.kicad_sch")
    (property "Sheetname" "FPGA power")
    (property "Val" "4u7")
    (property "Voltage" "")
    (property "ki_description" " ")
    (attr smd)
    (fp_text reference "C14" (at 18.79 -8.96 180) (layer "B.SilkS")
        (effects (font (size 0.7 0.7) (thickness 0.15)) (justify left bottom mirror))
    )
    (fp_text value "C_4u7_0402" (at 0 -1.4 180) (layer "B.Fab") hide
        (effects (font (size 0.7 0.7) (thickness 0.15)) (justify left bottom mirror))
    )
    (fp_text user "${REFERENCE}" (at -0.932 -3.168 180) (layer "B.Fab") hide
        (effects (font (size 0.7 0.7) (thickness 0.15)) (justify left bottom mirror))
    )
    (fp_text user "License: Apache-2.0" (at -0.932 -5.17 180) (layer "B.Fab") hide
        (effects (font (size 0.7 0.7) (thickness 0.15)) (justify left bottom mirror))
    )
    (fp_text user "Author: Antmicro" (at -0.932 -4.17 180) (layer "B.Fab") hide
        (effects (font (size 0.7 0.7) (thickness 0.15)) (justify left bottom mirror))
    )
    (fp_rect (start -0.94 0.47) (end 0.94 -0.47)
      (stroke (width 0.05) (type solid)) (fill none) (layer "B.CrtYd"))
    (fp_rect (start -0.499 0.249) (end 0.499 -0.249)
      (stroke (width 0.15) (type solid)) (fill none) (layer "B.Fab"))
    (pad "1" smd roundrect (at -0.484 0) (size 0.59 0.64) (layers "B.Cu" "B.Paste" "B.Mask") (roundrect_rratio 0.25)
      (net 147 "1V0_SYS") (pintype "passive"))
    (pad "2" smd roundrect (at 0.484 0) (size 0.59 0.64) (layers "B.Cu" "B.Paste" "B.Mask") (roundrect_rratio 0.25)
      (net 9 "GND") (pintype "passive"))
  )
	(footprint "data-center-rdimm-ddr4-tester-footprints:C_0402_1005Metric" (layer "B.Cu")
    (at 193.75 88.725)
    (descr "Capacitor SMD 0402")
    (tags "capacitor SMD 0402")
    (property "Author" "Antmicro")
    (property "Dielectric" "")
    (property "License" "Apache-2.0")
    (property "MPN" "C1005X5R1E474M050BB")
    (property "Manufacturer" "TDK")
    (property "Sheetfile" "config-spi.kicad_sch")
    (property "Sheetname" "Config SPI flash")
    (property "Val" "470n")
    (property "Voltage" "")
    (property "ki_description" " ")
    (attr smd)
    (fp_text reference "C37" (at 3.05 0.355 180) (layer "B.SilkS")
        (effects (font (size 0.7 0.7) (thickness 0.15)) (justify left bottom mirror))
    )
    (fp_text value "C_470n_0402" (at 0 -1.4 180) (layer "B.Fab") hide
        (effects (font (size 0.7 0.7) (thickness 0.15)) (justify left bottom mirror))
    )
    (fp_text user "License: Apache-2.0" (at -0.932 -5.17 180) (layer "B.Fab") hide
        (effects (font (size 0.7 0.7) (thickness 0.15)) (justify left bottom mirror))
    )
    (fp_text user "${REFERENCE}" (at -0.932 -3.168 180) (layer "B.Fab") hide
        (effects (font (size 0.7 0.7) (thickness 0.15)) (justify left bottom mirror))
    )
    (fp_text user "Author: Antmicro" (at -0.932 -4.17 180) (layer "B.Fab") hide
        (effects (font (size 0.7 0.7) (thickness 0.15)) (justify left bottom mirror))
    )
    (fp_rect (start -0.94 0.47) (end 0.94 -0.47)
      (stroke (width 0.05) (type solid)) (fill none) (layer "B.CrtYd"))
    (fp_rect (start -0.499 0.249) (end 0.499 -0.249)
      (stroke (width 0.15) (type solid)) (fill none) (layer "B.Fab"))
    (pad "1" smd roundrect (at -0.484 0) (size 0.59 0.64) (layers "B.Cu" "B.Paste" "B.Mask") (roundrect_rratio 0.25)
      (net 143 "3V3_SYS") (pintype "passive"))
    (pad "2" smd roundrect (at 0.484 0) (size 0.59 0.64) (layers "B.Cu" "B.Paste" "B.Mask") (roundrect_rratio 0.25)
      (net 9 "GND") (pintype "passive"))
  )
	(footprint "data-center-rdimm-ddr4-tester-footprints:C_0402_1005Metric" (layer "B.Cu")
    (at 158.236328 79.860008 180)
    (descr "Capacitor SMD 0402")
    (tags "capacitor SMD 0402")
    (property "Author" "Antmicro")
    (property "Dielectric" "X5R")
    (property "License" "Apache-2.0")
    (property "MPN" "GRM155R61H104KE14D")
    (property "Manufacturer" "Murata")
    (property "Sheetfile" "hyperram.kicad_sch")
    (property "Sheetname" "HyperRAM")
    (property "Val" "100n")
    (property "Voltage" "50V")
    (property "ki_description" " ")
    (attr smd)
    (fp_text reference "C103" (at -1.32 0.59) (layer "B.SilkS")
        (effects (font (size 0.7 0.7) (thickness 0.15)) (justify left bottom mirror))
    )
    (fp_text value "C_100n_0402" (at 0 -1.4) (layer "B.Fab") hide
        (effects (font (size 0.7 0.7) (thickness 0.15)) (justify left bottom mirror))
    )
    (fp_text user "License: Apache-2.0" (at -0.932 -5.17) (layer "B.Fab") hide
        (effects (font (size 0.7 0.7) (thickness 0.15)) (justify left bottom mirror))
    )
    (fp_text user "Author: Antmicro" (at -0.932 -4.17) (layer "B.Fab") hide
        (effects (font (size 0.7 0.7) (thickness 0.15)) (justify left bottom mirror))
    )
    (fp_text user "${REFERENCE}" (at -0.932 -3.168) (layer "B.Fab") hide
        (effects (font (size 0.7 0.7) (thickness 0.15)) (justify left bottom mirror))
    )
    (fp_rect (start -0.94 0.47) (end 0.94 -0.47)
      (stroke (width 0.05) (type solid)) (fill none) (layer "B.CrtYd"))
    (fp_rect (start -0.499 0.249) (end 0.499 -0.249)
      (stroke (width 0.15) (type solid)) (fill none) (layer "B.Fab"))
    (pad "1" smd roundrect (at -0.484 0 180) (size 0.59 0.64) (layers "B.Cu" "B.Paste" "B.Mask") (roundrect_rratio 0.25)
      (net 143 "3V3_SYS") (pintype "passive"))
    (pad "2" smd roundrect (at 0.484 0 180) (size 0.59 0.64) (layers "B.Cu" "B.Paste" "B.Mask") (roundrect_rratio 0.25)
      (net 9 "GND") (pintype "passive"))
  )
	(footprint "data-center-rdimm-ddr4-tester-footprints:C_0402_1005Metric" locked (layer "B.Cu")
    (at 155.0156 82.5632 90)
    (descr "Capacitor SMD 0402")
    (tags "capacitor SMD 0402")
    (property "Author" "Antmicro")
    (property "Dielectric" "X5R")
    (property "License" "Apache-2.0")
    (property "MPN" "GRM155R61H104KE14D")
    (property "Manufacturer" "Murata")
    (property "Sheetfile" "hyperram.kicad_sch")
    (property "Sheetname" "HyperRAM")
    (property "Val" "100n")
    (property "Voltage" "50V")
    (property "ki_description" " ")
    (attr smd)
    (fp_text reference "C104" (at 1.2832 1.3144 270) (layer "B.SilkS")
        (effects (font (size 0.7 0.7) (thickness 0.15)) (justify left bottom mirror))
    )
    (fp_text value "C_100n_0402" (at 0 -1.4 270) (layer "B.Fab") hide
        (effects (font (size 0.7 0.7) (thickness 0.15)) (justify left bottom mirror))
    )
    (fp_text user "Author: Antmicro" (at -0.932 -4.17 270) (layer "B.Fab") hide
        (effects (font (size 0.7 0.7) (thickness 0.15)) (justify left bottom mirror))
    )
    (fp_text user "${REFERENCE}" (at -0.932 -3.168 270) (layer "B.Fab") hide
        (effects (font (size 0.7 0.7) (thickness 0.15)) (justify left bottom mirror))
    )
    (fp_text user "License: Apache-2.0" (at -0.932 -5.17 270) (layer "B.Fab") hide
        (effects (font (size 0.7 0.7) (thickness 0.15)) (justify left bottom mirror))
    )
    (fp_rect (start -0.94 0.47) (end 0.94 -0.47)
      (stroke (width 0.05) (type solid)) (fill none) (layer "B.CrtYd"))
    (fp_rect (start -0.499 0.249) (end 0.499 -0.249)
      (stroke (width 0.15) (type solid)) (fill none) (layer "B.Fab"))
    (pad "1" smd roundrect locked (at -0.484 0 90) (size 0.59 0.64) (layers "B.Cu" "B.Paste" "B.Mask") (roundrect_rratio 0.25)
      (net 143 "3V3_SYS") (pintype "passive"))
    (pad "2" smd roundrect locked (at 0.484 0 90) (size 0.59 0.64) (layers "B.Cu" "B.Paste" "B.Mask") (roundrect_rratio 0.25)
      (net 9 "GND") (pintype "passive"))
  )
	(footprint "data-center-rdimm-ddr4-tester-footprints:C_0402_1005Metric" (layer "B.Cu")
    (at 153.7 79.1 180)
    (descr "Capacitor SMD 0402")
    (tags "capacitor SMD 0402")
    (property "Author" "Antmicro")
    (property "Dielectric" "X5R")
    (property "License" "Apache-2.0")
    (property "MPN" "GRM155R61H104KE14D")
    (property "Manufacturer" "Murata")
    (property "Sheetfile" "hyperram.kicad_sch")
    (property "Sheetname" "HyperRAM")
    (property "Val" "100n")
    (property "Voltage" "50V")
    (property "ki_description" " ")
    (attr smd)
    (fp_text reference "C105" (at -1.32 0.59) (layer "B.SilkS")
        (effects (font (size 0.7 0.7) (thickness 0.15)) (justify left bottom mirror))
    )
    (fp_text value "C_100n_0402" (at 0 -1.4) (layer "B.Fab") hide
        (effects (font (size 0.7 0.7) (thickness 0.15)) (justify left bottom mirror))
    )
    (fp_text user "Author: Antmicro" (at -0.932 -4.17) (layer "B.Fab") hide
        (effects (font (size 0.7 0.7) (thickness 0.15)) (justify left bottom mirror))
    )
    (fp_text user "${REFERENCE}" (at -0.932 -3.168) (layer "B.Fab") hide
        (effects (font (size 0.7 0.7) (thickness 0.15)) (justify left bottom mirror))
    )
    (fp_text user "License: Apache-2.0" (at -0.932 -5.17) (layer "B.Fab") hide
        (effects (font (size 0.7 0.7) (thickness 0.15)) (justify left bottom mirror))
    )
    (fp_rect (start -0.94 0.47) (end 0.94 -0.47)
      (stroke (width 0.05) (type solid)) (fill none) (layer "B.CrtYd"))
    (fp_rect (start -0.499 0.249) (end 0.499 -0.249)
      (stroke (width 0.15) (type solid)) (fill none) (layer "B.Fab"))
    (pad "1" smd roundrect (at -0.484 0 180) (size 0.59 0.64) (layers "B.Cu" "B.Paste" "B.Mask") (roundrect_rratio 0.25)
      (net 143 "3V3_SYS") (pintype "passive"))
    (pad "2" smd roundrect (at 0.484 0 180) (size 0.59 0.64) (layers "B.Cu" "B.Paste" "B.Mask") (roundrect_rratio 0.25)
      (net 9 "GND") (pintype "passive"))
  )
	(footprint "data-center-rdimm-ddr4-tester-footprints:C_0201" (layer "B.Cu")
    (at 184.186328 86.560008 90)
    (descr "Capacitor SMD 0201")
    (tags "capacitor SMD 0201")
    (property "Author" "Antmicro")
    (property "Dielectric" "")
    (property "License" "Apache-2.0")
    (property "MPN" "CC0201KRX6S5BB104")
    (property "Manufacturer" "Yaego")
    (property "Sheetfile" "fpga-power.kicad_sch")
    (property "Sheetname" "FPGA power")
    (property "Val" "100n")
    (property "Voltage" "")
    (property "ki_description" " ")
    (attr smd)
    (fp_text reference "C58" (at 10.320008 17.933672 270) (layer "B.SilkS")
        (effects (font (size 0.7 0.7) (thickness 0.15)) (justify left bottom mirror))
    )
    (fp_text value "C_100n_0201" (at 0 -1.4 270) (layer "B.Fab") hide
        (effects (font (size 0.7 0.7) (thickness 0.15)) (justify left bottom mirror))
    )
    (fp_text user "${REFERENCE}" (at -0.72 -3.4 270) (layer "B.Fab") hide
        (effects (font (size 0.7 0.7) (thickness 0.15)) (justify left bottom mirror))
    )
    (fp_text user "License: Apache-2.0" (at -0.72 -4.4 270) (layer "B.Fab") hide
        (effects (font (size 0.7 0.7) (thickness 0.15)) (justify left bottom mirror))
    )
    (fp_text user "Author: Antmicro" (at -0.72 -5.4 270) (layer "B.Fab") hide
        (effects (font (size 0.7 0.7) (thickness 0.15)) (justify left bottom mirror))
    )
    (fp_rect (start -0.72 0.38) (end 0.72 -0.38)
      (stroke (width 0.05) (type solid)) (fill none) (layer "B.CrtYd"))
    (fp_rect (start 0.3 -0.15) (end -0.301 0.149)
      (stroke (width 0.15) (type solid)) (fill none) (layer "B.Fab"))
    (pad "" smd roundrect (at -0.349 0.002 90) (size 0.318 0.36) (layers "B.Paste") (roundrect_rratio 0.25))
    (pad "" smd roundrect (at 0.341 0.002 90) (size 0.318 0.36) (layers "B.Paste") (roundrect_rratio 0.25))
    (pad "1" smd roundrect (at -0.321 0.002 90) (size 0.46 0.4) (layers "B.Cu" "B.Mask") (roundrect_rratio 0.25)
      (net 147 "1V0_SYS") (pintype "passive"))
    (pad "2" smd roundrect (at 0.32 0.002 90) (size 0.46 0.4) (layers "B.Cu" "B.Mask") (roundrect_rratio 0.25)
      (net 9 "GND") (pintype "passive"))
  )
)
